# T6G (Grand Teton) — schematic netlist excerpt (pin names and nets, part order shuffled) for the footprints in the layout excerpt that follows; sources: Cadence DE-HDL packaged netlist, KiCad conversion of 04192023_DAF0TMB3IC0_F0TG_MB_C_brd_V02_OCP.brd

C1592  Q_CAP  0.1UF 25V 10% X7R  pkg 0402  page 145 : A = P3V3_AUX ; B = GND
R3656  Q_RES  10K 1% EMPTY  pkg 0402LF  page 234 : A = P3V3_AUX ; B = USB_HUB_OVCUR1

(kicad_pcb
	(version 20260206)
	(generator "pcbnew")
	(generator_version "10.0")
	(general
		(thickness 1.6)
		(legacy_teardrops no)
	)
	(paper "A4")
	(title_block
		(title "04192023_DAF0TMB3IC0_F0TG_MB_C_brd_V02_OCP.brd")
		(comment 1 "Grand Teton / footprints 1438-1439 of 8354")
	)
	(layers
		(0 "F.Cu" signal "TOP")
		(4 "In1.Cu" signal "GND")
		(6 "In2.Cu" signal "IN1")
		(8 "In3.Cu" signal "GND1")
		(10 "In4.Cu" signal "IN2")
		(12 "In5.Cu" signal "GND2")
		(14 "In6.Cu" signal "IN3")
		(16 "In7.Cu" signal "GND3")
		(18 "In8.Cu" signal "VCC")
		(20 "In9.Cu" signal "VCC1")
		(22 "In10.Cu" signal "GND4")
		(24 "In11.Cu" signal "IN4")
		(26 "In12.Cu" signal "GND5")
		(28 "In13.Cu" signal "IN5")
		(30 "In14.Cu" signal "GND6")
		(32 "In15.Cu" signal "IN6")
		(34 "In16.Cu" signal "GND7")
		(2 "B.Cu" signal "BOTTOM")
		(9 "F.Adhes" user "F.Adhesive")
		(11 "B.Adhes" user "B.Adhesive")
		(13 "F.Paste" user "Package Geometry/Pastemask Top")
		(15 "B.Paste" user "Package Geometry/Pastemask Bottom")
		(5 "F.SilkS" user "Ref Des/Silkscreen Top")
		(7 "B.SilkS" user "Ref Des/Silkscreen Bottom")
		(1 "F.Mask" user "Board Geometry/Soldermask Top")
		(3 "B.Mask" user "Board Geometry/Soldermask Bottom")
		(17 "Dwgs.User" user "User.Drawings")
		(19 "Cmts.User" user "User.Comments")
		(21 "Eco1.User" user "User.Eco1")
		(23 "Eco2.User" user "User.Eco2")
		(25 "Edge.Cuts" user "Board Geometry/Outline")
		(27 "Margin" user)
		(31 "F.CrtYd" user "Package Geometry/Place Bound Top")
		(29 "B.CrtYd" user "Package Geometry/Place Bound Bottom")
		(35 "F.Fab" user "Ref Des/Assembly Top")
		(33 "B.Fab" user "Ref Des/Assembly Bottom")
	)
	(footprint ""
		(layer "F.Cu")
		(at 257.894836 -74.373994 90)
		(property "Reference" "C1592"
			(at 0 0 90)
			(layer "F.SilkS")
			(hide yes)
			(effects
				(font
					(size 1.27 1.27)
				)
			)
		)
		(property "Value" ""
			(at 0 0 90)
			(layer "F.Fab")
			(effects
				(font
					(size 1.27 1.27)
				)
			)
		)
		(duplicate_pad_numbers_are_jumpers no)
		(fp_line
			(start 0.7874 -0.4064)
			(end 0.7874 0.4064)
			(stroke
				(width 0.1524)
				(type default)
			)
			(layer "F.SilkS")
		)
		(fp_line
			(start -0.7874 -0.4064)
			(end 0.7874 -0.4064)
			(stroke
				(width 0.1524)
				(type default)
			)
			(layer "F.SilkS")
		)
		(fp_line
			(start 0.7874 0.4064)
			(end -0.7874 0.4064)
			(stroke
				(width 0.1524)
				(type default)
			)
			(layer "F.SilkS")
		)
		(fp_line
			(start -0.7874 0.4064)
			(end -0.7874 -0.4064)
			(stroke
				(width 0.1524)
				(type default)
			)
			(layer "F.SilkS")
		)
		(fp_line
			(start -0.12065 -0.305054)
			(end -0.12065 -0.2794)
			(stroke
				(width 0.1)
				(type default)
			)
			(layer "F.Fab")
		)
		(fp_line
			(start -0.67945 -0.305054)
			(end -0.12065 -0.305054)
			(stroke
				(width 0.1)
				(type default)
			)
			(layer "F.Fab")
		)
		(fp_line
			(start 0.67945 -0.3048)
			(end 0.67945 0.3048)
			(stroke
				(width 0.1)
				(type default)
			)
			(layer "F.Fab")
		)
		(fp_line
			(start 0.12065 -0.3048)
			(end 0.67945 -0.3048)
			(stroke
				(width 0.1)
				(type default)
			)
			(layer "F.Fab")
		)
		(fp_line
			(start 0.12065 -0.2794)
			(end 0.12065 -0.3048)
			(stroke
				(width 0.1)
				(type default)
			)
			(layer "F.Fab")
		)
		(fp_line
			(start -0.12065 -0.2794)
			(end 0.12065 -0.2794)
			(stroke
				(width 0.1)
				(type default)
			)
			(layer "F.Fab")
		)
		(fp_line
			(start 0.120396 0.2794)
			(end -0.12065 0.2794)
			(stroke
				(width 0.1)
				(type default)
			)
			(layer "F.Fab")
		)
		(fp_line
			(start -0.12065 0.2794)
			(end -0.12065 0.3048)
			(stroke
				(width 0.1)
				(type default)
			)
			(layer "F.Fab")
		)
		(fp_line
			(start 0.67945 0.3048)
			(end 0.120396 0.3048)
			(stroke
				(width 0.1)
				(type default)
			)
			(layer "F.Fab")
		)
		(fp_line
			(start 0.120396 0.3048)
			(end 0.120396 0.2794)
			(stroke
				(width 0.1)
				(type default)
			)
			(layer "F.Fab")
		)
		(fp_line
			(start -0.12065 0.3048)
			(end -0.67945 0.3048)
			(stroke
				(width 0.1)
				(type default)
			)
			(layer "F.Fab")
		)
		(fp_line
			(start -0.67945 0.3048)
			(end -0.67945 -0.305054)
			(stroke
				(width 0.1)
				(type default)
			)
			(layer "F.Fab")
		)
		(pad "1" smd circle
			(at -0.40005 0 90)
			(size 0 0)
			(layers "F.Cu" "F.Mask" "F.Paste")
			(net "P3V3_AUX")
		)
		(pad "2" smd circle
			(at 0.40005 0 90)
			(size 0 0)
			(layers "F.Cu" "F.Mask" "F.Paste")
			(net "GND")
		)
	)
	(footprint ""
		(layer "F.Cu")
		(at 21.176996 -100.54971 180)
		(property "Reference" "R3656"
			(at 0 0 180)
			(layer "F.SilkS")
			(hide yes)
			(effects
				(font
					(size 1.27 1.27)
				)
			)
		)
		(property "Value" ""
			(at 0 0 180)
			(layer "F.Fab")
			(effects
				(font
					(size 1.27 1.27)
				)
			)
		)
		(duplicate_pad_numbers_are_jumpers no)
		(fp_line
			(start 0.7874 0.4064)
			(end -0.7874 0.4064)
			(stroke
				(width 0.1524)
				(type default)
			)
			(layer "F.SilkS")
		)
		(fp_line
			(start 0.7874 -0.4064)
			(end 0.7874 0.4064)
			(stroke
				(width 0.1524)
				(type default)
			)
			(layer "F.SilkS")
		)
		(fp_line
			(start -0.7874 0.4064)
			(end -0.7874 -0.4064)
			(stroke
				(width 0.1524)
				(type default)
			)
			(layer "F.SilkS")
		)
		(fp_line
			(start -0.7874 -0.4064)
			(end 0.7874 -0.4064)
			(stroke
				(width 0.1524)
				(type default)
			)
			(layer "F.SilkS")
		)
		(fp_line
			(start 0.67945 0.3048)
			(end 0.120396 0.3048)
			(stroke
				(width 0.1)
				(type default)
			)
			(layer "F.Fab")
		)
		(fp_line
			(start 0.67945 -0.3048)
			(end 0.67945 0.3048)
			(stroke
				(width 0.1)
				(type default)
			)
			(layer "F.Fab")
		)
		(fp_line
			(start 0.12065 -0.2794)
			(end 0.12065 -0.3048)
			(stroke
				(width 0.1)
				(type default)
			)
			(layer "F.Fab")
		)
		(fp_line
			(start 0.12065 -0.3048)
			(end 0.67945 -0.3048)
			(stroke
				(width 0.1)
				(type default)
			)
			(layer "F.Fab")
		)
		(fp_line
			(start 0.120396 0.3048)
			(end 0.120396 0.2794)
			(stroke
				(width 0.1)
				(type default)
			)
			(layer "F.Fab")
		)
		(fp_line
			(start 0.120396 0.2794)
			(end -0.12065 0.2794)
			(stroke
				(width 0.1)
				(type default)
			)
			(layer "F.Fab")
		)
		(fp_line
			(start -0.12065 0.3048)
			(end -0.67945 0.3048)
			(stroke
				(width 0.1)
				(type default)
			)
			(layer "F.Fab")
		)
		(fp_line
			(start -0.12065 0.2794)
			(end -0.12065 0.3048)
			(stroke
				(width 0.1)
				(type default)
			)
			(layer "F.Fab")
		)
		(fp_line
			(start -0.12065 -0.2794)
			(end 0.12065 -0.2794)
			(stroke
				(width 0.1)
				(type default)
			)
			(layer "F.Fab")
		)
		(fp_line
			(start -0.12065 -0.305054)
			(end -0.12065 -0.2794)
			(stroke
				(width 0.1)
				(type default)
			)
			(layer "F.Fab")
		)
		(fp_line
			(start -0.67945 0.3048)
			(end -0.67945 -0.305054)
			(stroke
				(width 0.1)
				(type default)
			)
			(layer "F.Fab")
		)
		(fp_line
			(start -0.67945 -0.305054)
			(end -0.12065 -0.305054)
			(stroke
				(width 0.1)
				(type default)
			)
			(layer "F.Fab")
		)
		(pad "1" smd circle
			(at -0.40005 0 180)
			(size 0 0)
			(layers "F.Cu" "F.Mask" "F.Paste")
			(net "P3V3_AUX")
		)
		(pad "2" smd circle
			(at 0.40005 0 180)
			(size 0 0)
			(layers "F.Cu" "F.Mask" "F.Paste")
			(net "USB_HUB_OVCUR1")
		)
	)
)
